# S9S_MB_2U (Grand Teton) — schematic netlist excerpt (pin names and nets, part order shuffled) for the footprints in the layout excerpt that follows; sources: Cadence DE-HDL packaged netlist, KiCad conversion of 03242023_DA0F0TMBIJ0_F0T_Motherboard_J_brd_V01_OCP.brd

C941  Q_CAP_DIFFBUS  DIFF BUS_0.22UF 6.3V 20% X6S  pkg C0201  page 173 : \1\ = P5E_CPU0_PE2_TX_C_DP<12> ; \2\ = P5E_CPU0_PE2_TX_DP<12>
PR3789  Q_RES  25.5K 1% CHIP  pkg 0402LF  page 156 : A = P3V3_AUX ; B = P3V3_OCP_UV_1
PR3854  Q_RES  10K 1% CHIP  pkg 0402LF  page 163 : A = P12V_OCP_OV_FB_2 ; B = GND

(kicad_pcb
	(version 20260206)
	(generator "pcbnew")
	(generator_version "10.0")
	(general
		(thickness 1.6)
		(legacy_teardrops no)
	)
	(paper "A4")
	(title_block
		(title "03242023_DA0F0TMBIJ0_F0T_Motherboard_J_brd_V01_OCP.brd")
		(comment 1 "Grand Teton / footprints 628-630 of 6105")
	)
	(layers
		(0 "F.Cu" signal "TOP")
		(4 "In1.Cu" signal "GND")
		(6 "In2.Cu" signal "IN1")
		(8 "In3.Cu" signal "GND1")
		(10 "In4.Cu" signal "IN2")
		(12 "In5.Cu" signal "GND2")
		(14 "In6.Cu" signal "IN3")
		(16 "In7.Cu" signal "GND3")
		(18 "In8.Cu" signal "VCC")
		(20 "In9.Cu" signal "VCC1")
		(22 "In10.Cu" signal "GND4")
		(24 "In11.Cu" signal "IN4")
		(26 "In12.Cu" signal "GND5")
		(28 "In13.Cu" signal "IN5")
		(30 "In14.Cu" signal "GND6")
		(32 "In15.Cu" signal "IN6")
		(34 "In16.Cu" signal "GND7")
		(2 "B.Cu" signal "BOTTOM")
		(9 "F.Adhes" user "F.Adhesive")
		(11 "B.Adhes" user "B.Adhesive")
		(13 "F.Paste" user "Package Geometry/Pastemask Top")
		(15 "B.Paste" user "Package Geometry/Pastemask Bottom")
		(5 "F.SilkS" user "Ref Des/Silkscreen Top")
		(7 "B.SilkS" user "Ref Des/Silkscreen Bottom")
		(1 "F.Mask" user "Board Geometry/Soldermask Top")
		(3 "B.Mask" user "Board Geometry/Soldermask Bottom")
		(17 "Dwgs.User" user "User.Drawings")
		(19 "Cmts.User" user "User.Comments")
		(21 "Eco1.User" user "User.Eco1")
		(23 "Eco2.User" user "User.Eco2")
		(25 "Edge.Cuts" user "Board Geometry/Outline")
		(27 "Margin" user)
		(31 "F.CrtYd" user "Package Geometry/Place Bound Top")
		(29 "B.CrtYd" user "Package Geometry/Place Bound Bottom")
		(35 "F.Fab" user "Ref Des/Assembly Top")
		(33 "B.Fab" user "Ref Des/Assembly Bottom")
	)
	(footprint ""
		(layer "F.Cu")
		(at 63.877698 -26.99004 -90)
		(property "Reference" "PR3854"
			(at 0 0 270)
			(layer "F.SilkS")
			(hide yes)
			(effects
				(font
					(size 1.27 1.27)
				)
			)
		)
		(property "Value" ""
			(at 0 0 270)
			(layer "F.Fab")
			(effects
				(font
					(size 1.27 1.27)
				)
			)
		)
		(duplicate_pad_numbers_are_jumpers no)
		(fp_line
			(start -0.7874 0.4064)
			(end -0.7874 -0.4064)
			(stroke
				(width 0.1524)
				(type default)
			)
			(layer "F.SilkS")
		)
		(fp_line
			(start 0.7874 0.4064)
			(end -0.7874 0.4064)
			(stroke
				(width 0.1524)
				(type default)
			)
			(layer "F.SilkS")
		)
		(fp_line
			(start -0.7874 -0.4064)
			(end 0.7874 -0.4064)
			(stroke
				(width 0.1524)
				(type default)
			)
			(layer "F.SilkS")
		)
		(fp_line
			(start 0.7874 -0.4064)
			(end 0.7874 0.4064)
			(stroke
				(width 0.1524)
				(type default)
			)
			(layer "F.SilkS")
		)
		(fp_line
			(start -0.67945 0.3048)
			(end -0.67945 -0.305054)
			(stroke
				(width 0.1)
				(type default)
			)
			(layer "F.Fab")
		)
		(fp_line
			(start -0.12065 0.3048)
			(end -0.67945 0.3048)
			(stroke
				(width 0.1)
				(type default)
			)
			(layer "F.Fab")
		)
		(fp_line
			(start 0.120396 0.3048)
			(end 0.120396 0.2794)
			(stroke
				(width 0.1)
				(type default)
			)
			(layer "F.Fab")
		)
		(fp_line
			(start 0.67945 0.3048)
			(end 0.120396 0.3048)
			(stroke
				(width 0.1)
				(type default)
			)
			(layer "F.Fab")
		)
		(fp_line
			(start -0.12065 0.2794)
			(end -0.12065 0.3048)
			(stroke
				(width 0.1)
				(type default)
			)
			(layer "F.Fab")
		)
		(fp_line
			(start 0.120396 0.2794)
			(end -0.12065 0.2794)
			(stroke
				(width 0.1)
				(type default)
			)
			(layer "F.Fab")
		)
		(fp_line
			(start -0.12065 -0.2794)
			(end 0.12065 -0.2794)
			(stroke
				(width 0.1)
				(type default)
			)
			(layer "F.Fab")
		)
		(fp_line
			(start 0.12065 -0.2794)
			(end 0.12065 -0.3048)
			(stroke
				(width 0.1)
				(type default)
			)
			(layer "F.Fab")
		)
		(fp_line
			(start 0.12065 -0.3048)
			(end 0.67945 -0.3048)
			(stroke
				(width 0.1)
				(type default)
			)
			(layer "F.Fab")
		)
		(fp_line
			(start 0.67945 -0.3048)
			(end 0.67945 0.3048)
			(stroke
				(width 0.1)
				(type default)
			)
			(layer "F.Fab")
		)
		(fp_line
			(start -0.67945 -0.305054)
			(end -0.12065 -0.305054)
			(stroke
				(width 0.1)
				(type default)
			)
			(layer "F.Fab")
		)
		(fp_line
			(start -0.12065 -0.305054)
			(end -0.12065 -0.2794)
			(stroke
				(width 0.1)
				(type default)
			)
			(layer "F.Fab")
		)
		(pad "1" smd circle
			(at -0.40005 0 270)
			(size 0 0)
			(layers "F.Cu" "F.Mask" "F.Paste")
			(net "P12V_OCP_OV_FB_2")
		)
		(pad "2" smd circle
			(at 0.40005 0 270)
			(size 0 0)
			(layers "F.Cu" "F.Mask" "F.Paste")
			(net "GND")
		)
	)
	(footprint ""
		(layer "F.Cu")
		(at 429.299116 -109.26699 -90)
		(property "Reference" "PR3789"
			(at 0 0 270)
			(layer "F.SilkS")
			(hide yes)
			(effects
				(font
					(size 1.27 1.27)
				)
			)
		)
		(property "Value" ""
			(at 0 0 270)
			(layer "F.Fab")
			(effects
				(font
					(size 1.27 1.27)
				)
			)
		)
		(duplicate_pad_numbers_are_jumpers no)
		(fp_line
			(start -0.7874 0.4064)
			(end -0.7874 -0.4064)
			(stroke
				(width 0.1524)
				(type default)
			)
			(layer "F.SilkS")
		)
		(fp_line
			(start 0.7874 0.4064)
			(end -0.7874 0.4064)
			(stroke
				(width 0.1524)
				(type default)
			)
			(layer "F.SilkS")
		)
		(fp_line
			(start -0.7874 -0.4064)
			(end 0.7874 -0.4064)
			(stroke
				(width 0.1524)
				(type default)
			)
			(layer "F.SilkS")
		)
		(fp_line
			(start 0.7874 -0.4064)
			(end 0.7874 0.4064)
			(stroke
				(width 0.1524)
				(type default)
			)
			(layer "F.SilkS")
		)
		(fp_line
			(start -0.67945 0.3048)
			(end -0.67945 -0.305054)
			(stroke
				(width 0.1)
				(type default)
			)
			(layer "F.Fab")
		)
		(fp_line
			(start -0.12065 0.3048)
			(end -0.67945 0.3048)
			(stroke
				(width 0.1)
				(type default)
			)
			(layer "F.Fab")
		)
		(fp_line
			(start 0.120396 0.3048)
			(end 0.120396 0.2794)
			(stroke
				(width 0.1)
				(type default)
			)
			(layer "F.Fab")
		)
		(fp_line
			(start 0.67945 0.3048)
			(end 0.120396 0.3048)
			(stroke
				(width 0.1)
				(type default)
			)
			(layer "F.Fab")
		)
		(fp_line
			(start -0.12065 0.2794)
			(end -0.12065 0.3048)
			(stroke
				(width 0.1)
				(type default)
			)
			(layer "F.Fab")
		)
		(fp_line
			(start 0.120396 0.2794)
			(end -0.12065 0.2794)
			(stroke
				(width 0.1)
				(type default)
			)
			(layer "F.Fab")
		)
		(fp_line
			(start -0.12065 -0.2794)
			(end 0.12065 -0.2794)
			(stroke
				(width 0.1)
				(type default)
			)
			(layer "F.Fab")
		)
		(fp_line
			(start 0.12065 -0.2794)
			(end 0.12065 -0.3048)
			(stroke
				(width 0.1)
				(type default)
			)
			(layer "F.Fab")
		)
		(fp_line
			(start 0.12065 -0.3048)
			(end 0.67945 -0.3048)
			(stroke
				(width 0.1)
				(type default)
			)
			(layer "F.Fab")
		)
		(fp_line
			(start 0.67945 -0.3048)
			(end 0.67945 0.3048)
			(stroke
				(width 0.1)
				(type default)
			)
			(layer "F.Fab")
		)
		(fp_line
			(start -0.67945 -0.305054)
			(end -0.12065 -0.305054)
			(stroke
				(width 0.1)
				(type default)
			)
			(layer "F.Fab")
		)
		(fp_line
			(start -0.12065 -0.305054)
			(end -0.12065 -0.2794)
			(stroke
				(width 0.1)
				(type default)
			)
			(layer "F.Fab")
		)
		(pad "1" smd circle
			(at -0.40005 0 270)
			(size 0 0)
			(layers "F.Cu" "F.Mask" "F.Paste")
			(net "P3V3_AUX")
		)
		(pad "2" smd circle
			(at 0.40005 0 270)
			(size 0 0)
			(layers "F.Cu" "F.Mask" "F.Paste")
			(net "P3V3_OCP_UV_1")
		)
	)
	(footprint ""
		(layer "F.Cu")
		(at 380.58725 -402.371052 -90)
		(property "Reference" "C941"
			(at 0 0 270)
			(layer "F.SilkS")
			(hide yes)
			(effects
				(font
					(size 1.27 1.27)
				)
			)
		)
		(property "Value" ""
			(at 0 0 270)
			(layer "F.Fab")
			(effects
				(font
					(size 1.27 1.27)
				)
			)
		)
		(duplicate_pad_numbers_are_jumpers no)
		(fp_line
			(start -0.299974 0.150114)
			(end -0.299974 -0.150114)
			(stroke
				(width 0.1)
				(type default)
			)
			(layer "F.Fab")
		)
		(fp_line
			(start 0.299974 0.150114)
			(end -0.299974 0.150114)
			(stroke
				(width 0.1)
				(type default)
			)
			(layer "F.Fab")
		)
		(fp_line
			(start -0.299974 -0.150114)
			(end 0.299974 -0.150114)
			(stroke
				(width 0.1)
				(type default)
			)
			(layer "F.Fab")
		)
		(fp_line
			(start 0.299974 -0.150114)
			(end 0.299974 0.150114)
			(stroke
				(width 0.1)
				(type default)
			)
			(layer "F.Fab")
		)
		(pad "1" smd rect
			(at -0.2667 0 270)
			(size 0.3048 0.381)
			(layers "F.Cu" "F.Mask" "F.Paste")
			(net "P5E_CPU0_PE2_TX_C_DP<12>")
		)
		(pad "2" smd rect
			(at 0.2667 0 270)
			(size 0.3048 0.381)
			(layers "F.Cu" "F.Mask" "F.Paste")
			(net "P5E_CPU0_PE2_TX_DP<12>")
		)
	)
)
